(kicad_pcb
	(version 20241229)
	(generator "pcbnew")
	(generator_version "9.0")
	(general
		(thickness 1.292)
		(legacy_teardrops no)
	)
	(paper "A4")
	(title_block
		(title "LPDDR5 Testbed")
		(date "2023-12-19")
		(rev "1.0.0")
		(comment 9 "footprint 12 of 160 (U1), pads 1-89 of 315")
	)
	(layers
		(0 "F.Cu" signal)
		(4 "In1.Cu" power)
		(6 "In2.Cu" power)
		(8 "In3.Cu" signal)
		(10 "In4.Cu" signal)
		(2 "B.Cu" signal)
		(9 "F.Adhes" user "F.Adhesive")
		(11 "B.Adhes" user "B.Adhesive")
		(13 "F.Paste" user)
		(15 "B.Paste" user)
		(5 "F.SilkS" user "F.Silkscreen")
		(7 "B.SilkS" user "B.Silkscreen")
		(1 "F.Mask" user)
		(3 "B.Mask" user)
		(17 "Dwgs.User" user "User.Drawings")
		(19 "Cmts.User" user "User.Comments")
		(21 "Eco1.User" user "User.Eco1")
		(23 "Eco2.User" user "User.Eco2")
		(25 "Edge.Cuts" user)
		(27 "Margin" user)
		(31 "F.CrtYd" user "F.Courtyard")
		(29 "B.CrtYd" user "B.Courtyard")
		(35 "F.Fab" user)
		(33 "B.Fab" user)
	)
	(footprint "antmicro-footprints:BGA-315_12.4x15mm_Layout15x21_P0.8x0.7mm"
		(layer "F.Cu")
		(at 134.775 80 90)
		(property "Reference" "U1"
			(at 6.8 7.025 0)
			(unlocked yes)
			(layer "F.SilkS")
			(effects
				(font
					(size 0.7 0.7)
					(thickness 0.15)
				)
				(justify left bottom)
			)
		)
		(property "Value" "MT62F1G32D4DR-031"
			(at 0 8.9 90)
			(layer "F.Fab")
			(effects
				(font
					(size 0.7 0.7)
					(thickness 0.15)
				)
				(justify left bottom)
			)
		)
		(property "Author" "Antmicro"
			(at 214.775 -54.775 0)
			(layer "F.Fab")
			(hide yes)
			(effects
				(font
					(size 1 1)
					(thickness 0.15)
				)
			)
		)
		(property "License" "Apache-2.0"
			(at 214.775 -54.775 0)
			(layer "F.Fab")
			(hide yes)
			(effects
				(font
					(size 1 1)
					(thickness 0.15)
				)
			)
		)
		(property "MPN" "MT62F1G32D4DR-031 WT:B"
			(at 214.775 -54.775 0)
			(layer "F.Fab")
			(hide yes)
			(effects
				(font
					(size 1 1)
					(thickness 0.15)
				)
			)
		)
		(property "Manufacturer" "Micron Technology"
			(at 214.775 -54.775 0)
			(layer "F.Fab")
			(hide yes)
			(effects
				(font
					(size 1 1)
					(thickness 0.15)
				)
			)
		)
		(sheetname "LPDDR5")
		(sheetfile "lpddr5.kicad_sch")
		(attr smd)
		(pad "A1" smd circle
			(at -5.6 -7 90)
			(size 0.41 0.41)
			(layers "F.Cu" "F.Mask" "F.Paste")
			(net 21 "unconnected-(U1-PadA1)")
			(pinfunction "NC")
			(pintype "no_connect")
		)
		(pad "A2" smd circle
			(at -4.8 -7 90)
			(size 0.41 0.41)
			(layers "F.Cu" "F.Mask" "F.Paste")
			(net 22 "unconnected-(U1-PadA2)")
			(pinfunction "NC")
			(pintype "no_connect")
		)
		(pad "A3" smd circle
			(at -4 -7 90)
			(size 0.41 0.41)
			(layers "F.Cu" "F.Mask" "F.Paste")
			(net 4 "+0V5")
			(pinfunction "VDDQ")
			(pintype "passive")
		)
		(pad "A4" smd circle
			(at -3.2 -7 90)
			(size 0.41 0.41)
			(layers "F.Cu" "F.Mask" "F.Paste")
			(net 201 "/LPDDR5/LPDDR5_A.DMI0")
			(pinfunction "DMI0_A")
			(pintype "passive")
		)
		(pad "A5" smd circle
			(at -2.4 -7 90)
			(size 0.41 0.41)
			(layers "F.Cu" "F.Mask" "F.Paste")
			(net 14 "GND")
			(pinfunction "VSS")
			(pintype "passive")
		)
		(pad "A6" smd circle
			(at -1.6 -7 90)
			(size 0.41 0.41)
			(layers "F.Cu" "F.Mask" "F.Paste")
			(net 12 "+0V9")
			(pinfunction "VDD2L")
			(pintype "passive")
		)
		(pad "A7" smd circle
			(at -0.8 -7 90)
			(size 0.41 0.41)
			(layers "F.Cu" "F.Mask" "F.Paste")
			(net 13 "+1V05")
			(pinfunction "VDD2H")
			(pintype "passive")
		)
		(pad "A8" smd circle
			(at 0 -7 90)
			(size 0.41 0.41)
			(layers "F.Cu" "F.Mask" "F.Paste")
			(net 13 "+1V05")
			(pinfunction "VDD2H")
			(pintype "passive")
		)
		(pad "A9" smd circle
			(at 0.8 -7 90)
			(size 0.41 0.41)
			(layers "F.Cu" "F.Mask" "F.Paste")
			(net 13 "+1V05")
			(pinfunction "VDD2H")
			(pintype "passive")
		)
		(pad "A10" smd circle
			(at 1.6 -7 90)
			(size 0.41 0.41)
			(layers "F.Cu" "F.Mask" "F.Paste")
			(net 12 "+0V9")
			(pinfunction "VDD2L")
			(pintype "passive")
		)
		(pad "A11" smd circle
			(at 2.4 -7 90)
			(size 0.41 0.41)
			(layers "F.Cu" "F.Mask" "F.Paste")
			(net 14 "GND")
			(pinfunction "VSS")
			(pintype "passive")
		)
		(pad "A12" smd circle
			(at 3.2 -7 90)
			(size 0.41 0.41)
			(layers "F.Cu" "F.Mask" "F.Paste")
			(net 190 "/LPDDR5/LPDDR5_A.DMI1")
			(pinfunction "DMI1_A")
			(pintype "passive")
		)
		(pad "A13" smd circle
			(at 4 -7 90)
			(size 0.41 0.41)
			(layers "F.Cu" "F.Mask" "F.Paste")
			(net 4 "+0V5")
			(pinfunction "VDDQ")
			(pintype "passive")
		)
		(pad "A14" smd circle
			(at 4.8 -7 90)
			(size 0.41 0.41)
			(layers "F.Cu" "F.Mask" "F.Paste")
			(net 2 "unconnected-(U1-PadA14)")
			(pinfunction "NC")
			(pintype "no_connect")
		)
		(pad "A15" smd circle
			(at 5.6 -7 90)
			(size 0.41 0.41)
			(layers "F.Cu" "F.Mask" "F.Paste")
			(net 3 "unconnected-(U1-PadA15)")
			(pinfunction "NC")
			(pintype "no_connect")
		)
		(pad "AA1" smd circle
			(at -5.6 7 90)
			(size 0.41 0.41)
			(layers "F.Cu" "F.Mask" "F.Paste")
			(net 26 "unconnected-(U1-PadAA1)")
			(pinfunction "NC")
			(pintype "no_connect")
		)
		(pad "AA2" smd circle
			(at -4.8 7 90)
			(size 0.41 0.41)
			(layers "F.Cu" "F.Mask" "F.Paste")
			(net 27 "unconnected-(U1-PadAA2)")
			(pinfunction "NC")
			(pintype "no_connect")
		)
		(pad "AA3" smd circle
			(at -4 7 90)
			(size 0.41 0.41)
			(layers "F.Cu" "F.Mask" "F.Paste")
			(net 4 "+0V5")
			(pinfunction "VDDQ")
			(pintype "passive")
		)
		(pad "AA4" smd circle
			(at -3.2 7 90)
			(size 0.41 0.41)
			(layers "F.Cu" "F.Mask" "F.Paste")
			(net 223 "/LPDDR5/LPDDR5_B.DMI1")
			(pinfunction "DMI1_B")
			(pintype "passive")
		)
		(pad "AA5" smd circle
			(at -2.4 7 90)
			(size 0.41 0.41)
			(layers "F.Cu" "F.Mask" "F.Paste")
			(net 14 "GND")
			(pinfunction "VSS")
			(pintype "passive")
		)
		(pad "AA6" smd circle
			(at -1.6 7 90)
			(size 0.41 0.41)
			(layers "F.Cu" "F.Mask" "F.Paste")
			(net 12 "+0V9")
			(pinfunction "VDD2L")
			(pintype "passive")
		)
		(pad "AA7" smd circle
			(at -0.8 7 90)
			(size 0.41 0.41)
			(layers "F.Cu" "F.Mask" "F.Paste")
			(net 13 "+1V05")
			(pinfunction "VDD2H")
			(pintype "passive")
		)
		(pad "AA8" smd circle
			(at 0 7 90)
			(size 0.41 0.41)
			(layers "F.Cu" "F.Mask" "F.Paste")
			(net 13 "+1V05")
			(pinfunction "VDD2H")
			(pintype "passive")
		)
		(pad "AA9" smd circle
			(at 0.8 7 90)
			(size 0.41 0.41)
			(layers "F.Cu" "F.Mask" "F.Paste")
			(net 13 "+1V05")
			(pinfunction "VDD2H")
			(pintype "passive")
		)
		(pad "AA10" smd circle
			(at 1.6 7 90)
			(size 0.41 0.41)
			(layers "F.Cu" "F.Mask" "F.Paste")
			(net 12 "+0V9")
			(pinfunction "VDD2L")
			(pintype "passive")
		)
		(pad "AA11" smd circle
			(at 2.4 7 90)
			(size 0.41 0.41)
			(layers "F.Cu" "F.Mask" "F.Paste")
			(net 14 "GND")
			(pinfunction "VSS")
			(pintype "passive")
		)
		(pad "AA12" smd circle
			(at 3.2 7 90)
			(size 0.41 0.41)
			(layers "F.Cu" "F.Mask" "F.Paste")
			(net 212 "/LPDDR5/LPDDR5_B.DMI0")
			(pinfunction "DMI0_B")
			(pintype "passive")
		)
		(pad "AA13" smd circle
			(at 4 7 90)
			(size 0.41 0.41)
			(layers "F.Cu" "F.Mask" "F.Paste")
			(net 4 "+0V5")
			(pinfunction "VDDQ")
			(pintype "passive")
		)
		(pad "AA14" smd circle
			(at 4.8 7 90)
			(size 0.41 0.41)
			(layers "F.Cu" "F.Mask" "F.Paste")
			(net 23 "unconnected-(U1-PadAA14)")
			(pinfunction "NC")
			(pintype "no_connect")
		)
		(pad "AA15" smd circle
			(at 5.6 7 90)
			(size 0.41 0.41)
			(layers "F.Cu" "F.Mask" "F.Paste")
			(net 24 "unconnected-(U1-PadAA15)")
			(pinfunction "NC")
			(pintype "no_connect")
		)
		(pad "B1" smd circle
			(at -5.6 -6.3 90)
			(size 0.41 0.41)
			(layers "F.Cu" "F.Mask" "F.Paste")
			(net 28 "unconnected-(U1-PadB1)")
			(pinfunction "NC")
			(pintype "no_connect")
		)
		(pad "B2" smd circle
			(at -4.8 -6.3 90)
			(size 0.41 0.41)
			(layers "F.Cu" "F.Mask" "F.Paste")
			(net 4 "+0V5")
			(pinfunction "VDDQ")
			(pintype "passive")
		)
		(pad "B3" smd circle
			(at -4 -6.3 90)
			(size 0.41 0.41)
			(layers "F.Cu" "F.Mask" "F.Paste")
			(net 200 "/LPDDR5/LPDDR5_A.RDQS0_P")
			(pinfunction "RDQS0_t_A")
			(pintype "passive")
		)
		(pad "B4" smd circle
			(at -3.2 -6.3 90)
			(size 0.41 0.41)
			(layers "F.Cu" "F.Mask" "F.Paste")
			(net 14 "GND")
			(pinfunction "VSS")
			(pintype "passive")
		)
		(pad "B5" smd circle
			(at -2.4 -6.3 90)
			(size 0.41 0.41)
			(layers "F.Cu" "F.Mask" "F.Paste")
			(net 198 "/LPDDR5/LPDDR5_A.DQ4")
			(pinfunction "DQ4_A")
			(pintype "passive")
		)
		(pad "B6" smd circle
			(at -1.6 -6.3 90)
			(size 0.41 0.41)
			(layers "F.Cu" "F.Mask" "F.Paste")
			(net 12 "+0V9")
			(pinfunction "VDD2L")
			(pintype "passive")
		)
		(pad "B7" smd circle
			(at -0.8 -6.3 90)
			(size 0.41 0.41)
			(layers "F.Cu" "F.Mask" "F.Paste")
			(net 13 "+1V05")
			(pinfunction "VDD2H")
			(pintype "passive")
		)
		(pad "B8" smd circle
			(at 0 -6.3 90)
			(size 0.41 0.41)
			(layers "F.Cu" "F.Mask" "F.Paste")
			(net 14 "GND")
			(pinfunction "VSS")
			(pintype "passive")
		)
		(pad "B9" smd circle
			(at 0.8 -6.3 90)
			(size 0.41 0.41)
			(layers "F.Cu" "F.Mask" "F.Paste")
			(net 13 "+1V05")
			(pinfunction "VDD2H")
			(pintype "passive")
		)
		(pad "B10" smd circle
			(at 1.6 -6.3 90)
			(size 0.41 0.41)
			(layers "F.Cu" "F.Mask" "F.Paste")
			(net 12 "+0V9")
			(pinfunction "VDD2L")
			(pintype "passive")
		)
		(pad "B11" smd circle
			(at 2.4 -6.3 90)
			(size 0.41 0.41)
			(layers "F.Cu" "F.Mask" "F.Paste")
			(net 193 "/LPDDR5/LPDDR5_A.DQ12")
			(pinfunction "DQ12_A")
			(pintype "passive")
		)
		(pad "B12" smd circle
			(at 3.2 -6.3 90)
			(size 0.41 0.41)
			(layers "F.Cu" "F.Mask" "F.Paste")
			(net 14 "GND")
			(pinfunction "VSS")
			(pintype "passive")
		)
		(pad "B13" smd circle
			(at 4 -6.3 90)
			(size 0.41 0.41)
			(layers "F.Cu" "F.Mask" "F.Paste")
			(net 189 "/LPDDR5/LPDDR5_A.RDQS1_P")
			(pinfunction "RDQS1_t_A")
			(pintype "passive")
		)
		(pad "B14" smd circle
			(at 4.8 -6.3 90)
			(size 0.41 0.41)
			(layers "F.Cu" "F.Mask" "F.Paste")
			(net 4 "+0V5")
			(pinfunction "VDDQ")
			(pintype "passive")
		)
		(pad "B15" smd circle
			(at 5.6 -6.3 90)
			(size 0.41 0.41)
			(layers "F.Cu" "F.Mask" "F.Paste")
			(net 25 "unconnected-(U1-PadB15)")
			(pinfunction "NC")
			(pintype "no_connect")
		)
		(pad "C1" smd circle
			(at -5.6 -5.6 90)
			(size 0.41 0.41)
			(layers "F.Cu" "F.Mask" "F.Paste")
			(net 35 "+1V8")
			(pinfunction "VDD1")
			(pintype "passive")
		)
		(pad "C2" smd circle
			(at -4.8 -5.6 90)
			(size 0.41 0.41)
			(layers "F.Cu" "F.Mask" "F.Paste")
			(net 204 "/LPDDR5/LPDDR5_A.DQ1")
			(pinfunction "DQ1_A")
			(pintype "passive")
		)
		(pad "C3" smd circle
			(at -4 -5.6 90)
			(size 0.41 0.41)
			(layers "F.Cu" "F.Mask" "F.Paste")
			(net 4 "+0V5")
			(pinfunction "VDDQ")
			(pintype "passive")
		)
		(pad "C4" smd circle
			(at -3.2 -5.6 90)
			(size 0.41 0.41)
			(layers "F.Cu" "F.Mask" "F.Paste")
			(net 199 "/LPDDR5/LPDDR5_A.RDQS0_N")
			(pinfunction "RDQS0_c_A")
			(pintype "passive")
		)
		(pad "C5" smd circle
			(at -2.4 -5.6 90)
			(size 0.41 0.41)
			(layers "F.Cu" "F.Mask" "F.Paste")
			(net 14 "GND")
			(pinfunction "VSS")
			(pintype "passive")
		)
		(pad "C6" smd circle
			(at -1.6 -5.6 90)
			(size 0.41 0.41)
			(layers "F.Cu" "F.Mask" "F.Paste")
			(net 197 "/LPDDR5/LPDDR5_A.DQ5")
			(pinfunction "DQ5_A")
			(pintype "passive")
		)
		(pad "C7" smd circle
			(at -0.8 -5.6 90)
			(size 0.41 0.41)
			(layers "F.Cu" "F.Mask" "F.Paste")
			(net 13 "+1V05")
			(pinfunction "VDD2H")
			(pintype "passive")
		)
		(pad "C8" smd circle
			(at 0 -5.6 90)
			(size 0.41 0.41)
			(layers "F.Cu" "F.Mask" "F.Paste")
			(net 14 "GND")
			(pinfunction "VSS")
			(pintype "passive")
		)
		(pad "C9" smd circle
			(at 0.8 -5.6 90)
			(size 0.41 0.41)
			(layers "F.Cu" "F.Mask" "F.Paste")
			(net 13 "+1V05")
			(pinfunction "VDD2H")
			(pintype "passive")
		)
		(pad "C10" smd circle
			(at 1.6 -5.6 90)
			(size 0.41 0.41)
			(layers "F.Cu" "F.Mask" "F.Paste")
			(net 194 "/LPDDR5/LPDDR5_A.DQ13")
			(pinfunction "DQ13_A")
			(pintype "passive")
		)
		(pad "C11" smd circle
			(at 2.4 -5.6 90)
			(size 0.41 0.41)
			(layers "F.Cu" "F.Mask" "F.Paste")
			(net 14 "GND")
			(pinfunction "VSS")
			(pintype "passive")
		)
		(pad "C12" smd circle
			(at 3.2 -5.6 90)
			(size 0.41 0.41)
			(layers "F.Cu" "F.Mask" "F.Paste")
			(net 188 "/LPDDR5/LPDDR5_A.RDQS1_N")
			(pinfunction "RDQS1_c_A")
			(pintype "passive")
		)
		(pad "C13" smd circle
			(at 4 -5.6 90)
			(size 0.41 0.41)
			(layers "F.Cu" "F.Mask" "F.Paste")
			(net 4 "+0V5")
			(pinfunction "VDDQ")
			(pintype "passive")
		)
		(pad "C14" smd circle
			(at 4.8 -5.6 90)
			(size 0.41 0.41)
			(layers "F.Cu" "F.Mask" "F.Paste")
			(net 172 "/LPDDR5/LPDDR5_A.DQ9")
			(pinfunction "DQ9_A")
			(pintype "passive")
		)
		(pad "C15" smd circle
			(at 5.6 -5.6 90)
			(size 0.41 0.41)
			(layers "F.Cu" "F.Mask" "F.Paste")
			(net 35 "+1V8")
			(pinfunction "VDD1")
			(pintype "passive")
		)
		(pad "D1" smd circle
			(at -5.6 -4.9 90)
			(size 0.41 0.41)
			(layers "F.Cu" "F.Mask" "F.Paste")
			(net 205 "/LPDDR5/LPDDR5_A.DQ0")
			(pinfunction "DQ0_A")
			(pintype "passive")
		)
		(pad "D2" smd circle
			(at -4.8 -4.9 90)
			(size 0.41 0.41)
			(layers "F.Cu" "F.Mask" "F.Paste")
			(net 14 "GND")
			(pinfunction "VSS")
			(pintype "passive")
		)
		(pad "D3" smd circle
			(at -4 -4.9 90)
			(size 0.41 0.41)
			(layers "F.Cu" "F.Mask" "F.Paste")
			(net 202 "/LPDDR5/LPDDR5_A.DQ3")
			(pinfunction "DQ3_A")
			(pintype "passive")
		)
		(pad "D4" smd circle
			(at -3.2 -4.9 90)
			(size 0.41 0.41)
			(layers "F.Cu" "F.Mask" "F.Paste")
			(net 4 "+0V5")
			(pinfunction "VDDQ")
			(pintype "passive")
		)
		(pad "D5" smd circle
			(at -2.4 -4.9 90)
			(size 0.41 0.41)
			(layers "F.Cu" "F.Mask" "F.Paste")
			(net 46 "/LPDDR5/LPDDR5_A.WCK0_N")
			(pinfunction "WCK0_c_A")
			(pintype "passive")
		)
		(pad "D6" smd circle
			(at -1.6 -4.9 90)
			(size 0.41 0.41)
			(layers "F.Cu" "F.Mask" "F.Paste")
			(net 14 "GND")
			(pinfunction "VSS")
			(pintype "passive")
		)
		(pad "D7" smd circle
			(at -0.8 -4.9 90)
			(size 0.41 0.41)
			(layers "F.Cu" "F.Mask" "F.Paste")
			(net 14 "GND")
			(pinfunction "VSS")
			(pintype "passive")
		)
		(pad "D8" smd circle
			(at 0 -4.9 90)
			(size 0.41 0.41)
			(layers "F.Cu" "F.Mask" "F.Paste")
			(net 13 "+1V05")
			(pinfunction "VDD2H")
			(pintype "passive")
		)
		(pad "D9" smd circle
			(at 0.8 -4.9 90)
			(size 0.41 0.41)
			(layers "F.Cu" "F.Mask" "F.Paste")
			(net 14 "GND")
			(pinfunction "VSS")
			(pintype "passive")
		)
		(pad "D10" smd circle
			(at 1.6 -4.9 90)
			(size 0.41 0.41)
			(layers "F.Cu" "F.Mask" "F.Paste")
			(net 14 "GND")
			(pinfunction "VSS")
			(pintype "passive")
		)
		(pad "D11" smd circle
			(at 2.4 -4.9 90)
			(size 0.41 0.41)
			(layers "F.Cu" "F.Mask" "F.Paste")
			(net 47 "/LPDDR5/LPDDR5_A.WCK1_N")
			(pinfunction "WCK1_c_A")
			(pintype "passive")
		)
		(pad "D12" smd circle
			(at 3.2 -4.9 90)
			(size 0.41 0.41)
			(layers "F.Cu" "F.Mask" "F.Paste")
			(net 4 "+0V5")
			(pinfunction "VDDQ")
			(pintype "passive")
		)
		(pad "D13" smd circle
			(at 4 -4.9 90)
			(size 0.41 0.41)
			(layers "F.Cu" "F.Mask" "F.Paste")
			(net 183 "/LPDDR5/LPDDR5_A.DQ11")
			(pinfunction "DQ11_A")
			(pintype "passive")
		)
		(pad "D14" smd circle
			(at 4.8 -4.9 90)
			(size 0.41 0.41)
			(layers "F.Cu" "F.Mask" "F.Paste")
			(net 14 "GND")
			(pinfunction "VSS")
			(pintype "passive")
		)
		(pad "D15" smd circle
			(at 5.6 -4.9 90)
			(size 0.41 0.41)
			(layers "F.Cu" "F.Mask" "F.Paste")
			(net 128 "/LPDDR5/LPDDR5_A.DQ8")
			(pinfunction "DQ8_A")
			(pintype "passive")
		)
		(pad "E1" smd circle
			(at -5.6 -4.2 90)
			(size 0.41 0.41)
			(layers "F.Cu" "F.Mask" "F.Paste")
			(net 14 "GND")
			(pinfunction "VSS")
			(pintype "passive")
		)
		(pad "E2" smd circle
			(at -4.8 -4.2 90)
			(size 0.41 0.41)
			(layers "F.Cu" "F.Mask" "F.Paste")
			(net 203 "/LPDDR5/LPDDR5_A.DQ2")
			(pinfunction "DQ2_A")
			(pintype "passive")
		)
		(pad "E3" smd circle
			(at -4 -4.2 90)
			(size 0.41 0.41)
			(layers "F.Cu" "F.Mask" "F.Paste")
			(net 14 "GND")
			(pinfunction "VSS")
			(pintype "passive")
		)
		(pad "E4" smd circle
			(at -3.2 -4.2 90)
			(size 0.41 0.41)
			(layers "F.Cu" "F.Mask" "F.Paste")
			(net 45 "/LPDDR5/LPDDR5_A.WCK0_P")
			(pinfunction "WCK0_t_A")
			(pintype "passive")
		)
		(pad "E5" smd circle
			(at -2.4 -4.2 90)
			(size 0.41 0.41)
			(layers "F.Cu" "F.Mask" "F.Paste")
			(net 4 "+0V5")
			(pinfunction "VDDQ")
			(pintype "passive")
		)
		(pad "E6" smd circle
			(at -1.6 -4.2 90)
			(size 0.41 0.41)
			(layers "F.Cu" "F.Mask" "F.Paste")
			(net 196 "/LPDDR5/LPDDR5_A.DQ6")
			(pinfunction "DQ6_A")
			(pintype "passive")
		)
		(pad "E7" smd circle
			(at -0.8 -4.2 90)
			(size 0.41 0.41)
			(layers "F.Cu" "F.Mask" "F.Paste")
			(net 13 "+1V05")
			(pinfunction "VDD2H")
			(pintype "passive")
		)
		(pad "E8" smd circle
			(at 0 -4.2 90)
			(size 0.41 0.41)
			(layers "F.Cu" "F.Mask" "F.Paste")
			(net 14 "GND")
			(pinfunction "VSS")
			(pintype "passive")
		)
		(pad "E9" smd circle
			(at 0.8 -4.2 90)
			(size 0.41 0.41)
			(layers "F.Cu" "F.Mask" "F.Paste")
			(net 13 "+1V05")
			(pinfunction "VDD2H")
			(pintype "passive")
		)
		(pad "E10" smd circle
			(at 1.6 -4.2 90)
			(size 0.41 0.41)
			(layers "F.Cu" "F.Mask" "F.Paste")
			(net 192 "/LPDDR5/LPDDR5_A.DQ14")
			(pinfunction "DQ14_A")
			(pintype "passive")
		)
		(pad "E11" smd circle
			(at 2.4 -4.2 90)
			(size 0.41 0.41)
			(layers "F.Cu" "F.Mask" "F.Paste")
			(net 4 "+0V5")
			(pinfunction "VDDQ")
			(pintype "passive")
		)
		(pad "E12" smd circle
			(at 3.2 -4.2 90)
			(size 0.41 0.41)
			(layers "F.Cu" "F.Mask" "F.Paste")
			(net 48 "/LPDDR5/LPDDR5_A.WCK1_P")
			(pinfunction "WCK1_t_A")
			(pintype "passive")
		)
		(pad "E13" smd circle
			(at 4 -4.2 90)
			(size 0.41 0.41)
			(layers "F.Cu" "F.Mask" "F.Paste")
			(net 14 "GND")
			(pinfunction "VSS")
			(pintype "passive")
		)
		(pad "E14" smd circle
			(at 4.8 -4.2 90)
			(size 0.41 0.41)
			(layers "F.Cu" "F.Mask" "F.Paste")
			(net 139 "/LPDDR5/LPDDR5_A.DQ10")
			(pinfunction "DQ10_A")
			(pintype "passive")
		)
	)
)
